# T6G (Grand Teton) — schematic netlist excerpt (pin names and nets, part order shuffled) for the footprints in the layout excerpt that follows; sources: Cadence DE-HDL packaged netlist, KiCad conversion of 04192023_DAF0TMB3IC0_F0TG_MB_C_brd_V02_OCP.brd

C2497  Q_CAP  22UF 4V 20% X6S  pkg C0402  page 74 : A = PVDD11_S3_P1 ; B = GND
PR84  Q_RES  0 5% CHIP  pkg 0402LF  page 201 : A = PVDDCR_CPU1_P0_VOS1 ; B = PVDDCR_CPU1_P0

(kicad_pcb
	(version 20260206)
	(generator "pcbnew")
	(generator_version "10.0")
	(general
		(thickness 1.6)
		(legacy_teardrops no)
	)
	(paper "A4")
	(title_block
		(title "04192023_DAF0TMB3IC0_F0TG_MB_C_brd_V02_OCP.brd")
		(comment 1 "Grand Teton / footprints 7486-7487 of 8354")
	)
	(layers
		(0 "F.Cu" signal "TOP")
		(4 "In1.Cu" signal "GND")
		(6 "In2.Cu" signal "IN1")
		(8 "In3.Cu" signal "GND1")
		(10 "In4.Cu" signal "IN2")
		(12 "In5.Cu" signal "GND2")
		(14 "In6.Cu" signal "IN3")
		(16 "In7.Cu" signal "GND3")
		(18 "In8.Cu" signal "VCC")
		(20 "In9.Cu" signal "VCC1")
		(22 "In10.Cu" signal "GND4")
		(24 "In11.Cu" signal "IN4")
		(26 "In12.Cu" signal "GND5")
		(28 "In13.Cu" signal "IN5")
		(30 "In14.Cu" signal "GND6")
		(32 "In15.Cu" signal "IN6")
		(34 "In16.Cu" signal "GND7")
		(2 "B.Cu" signal "BOTTOM")
		(9 "F.Adhes" user "F.Adhesive")
		(11 "B.Adhes" user "B.Adhesive")
		(13 "F.Paste" user "Package Geometry/Pastemask Top")
		(15 "B.Paste" user "Package Geometry/Pastemask Bottom")
		(5 "F.SilkS" user "Ref Des/Silkscreen Top")
		(7 "B.SilkS" user "Ref Des/Silkscreen Bottom")
		(1 "F.Mask" user "Board Geometry/Soldermask Top")
		(3 "B.Mask" user "Board Geometry/Soldermask Bottom")
		(17 "Dwgs.User" user "User.Drawings")
		(19 "Cmts.User" user "User.Comments")
		(21 "Eco1.User" user "User.Eco1")
		(23 "Eco2.User" user "User.Eco2")
		(25 "Edge.Cuts" user "Board Geometry/Outline")
		(27 "Margin" user)
		(31 "F.CrtYd" user "Package Geometry/Place Bound Top")
		(29 "B.CrtYd" user "Package Geometry/Place Bound Bottom")
		(35 "F.Fab" user "Ref Des/Assembly Top")
		(33 "B.Fab" user "Ref Des/Assembly Bottom")
	)
	(footprint ""
		(layer "B.Cu")
		(at 331.39761 -337.638898 -90)
		(property "Reference" "PR84"
			(at 0 0 90)
			(layer "B.SilkS")
			(hide yes)
			(effects
				(font
					(size 1.27 1.27)
				)
				(justify mirror)
			)
		)
		(property "Value" ""
			(at 0 0 90)
			(layer "B.Fab")
			(effects
				(font
					(size 1.27 1.27)
				)
				(justify mirror)
			)
		)
		(duplicate_pad_numbers_are_jumpers no)
		(fp_line
			(start -0.7874 0.4064)
			(end 0.7874 0.4064)
			(stroke
				(width 0.1524)
				(type default)
			)
			(layer "B.SilkS")
		)
		(fp_line
			(start 0.7874 0.4064)
			(end 0.7874 -0.4064)
			(stroke
				(width 0.1524)
				(type default)
			)
			(layer "B.SilkS")
		)
		(fp_line
			(start -0.7874 -0.4064)
			(end -0.7874 0.4064)
			(stroke
				(width 0.1524)
				(type default)
			)
			(layer "B.SilkS")
		)
		(fp_line
			(start 0.7874 -0.4064)
			(end -0.7874 -0.4064)
			(stroke
				(width 0.1524)
				(type default)
			)
			(layer "B.SilkS")
		)
		(fp_line
			(start -0.67945 0.3048)
			(end -0.120396 0.3048)
			(stroke
				(width 0.1)
				(type default)
			)
			(layer "B.Fab")
		)
		(fp_line
			(start -0.120396 0.3048)
			(end -0.120396 0.2794)
			(stroke
				(width 0.1)
				(type default)
			)
			(layer "B.Fab")
		)
		(fp_line
			(start 0.12065 0.3048)
			(end 0.67945 0.3048)
			(stroke
				(width 0.1)
				(type default)
			)
			(layer "B.Fab")
		)
		(fp_line
			(start 0.67945 0.3048)
			(end 0.67945 -0.305054)
			(stroke
				(width 0.1)
				(type default)
			)
			(layer "B.Fab")
		)
		(fp_line
			(start -0.120396 0.2794)
			(end 0.12065 0.2794)
			(stroke
				(width 0.1)
				(type default)
			)
			(layer "B.Fab")
		)
		(fp_line
			(start 0.12065 0.2794)
			(end 0.12065 0.3048)
			(stroke
				(width 0.1)
				(type default)
			)
			(layer "B.Fab")
		)
		(fp_line
			(start -0.12065 -0.2794)
			(end -0.12065 -0.3048)
			(stroke
				(width 0.1)
				(type default)
			)
			(layer "B.Fab")
		)
		(fp_line
			(start 0.12065 -0.2794)
			(end -0.12065 -0.2794)
			(stroke
				(width 0.1)
				(type default)
			)
			(layer "B.Fab")
		)
		(fp_line
			(start -0.67945 -0.3048)
			(end -0.67945 0.3048)
			(stroke
				(width 0.1)
				(type default)
			)
			(layer "B.Fab")
		)
		(fp_line
			(start -0.12065 -0.3048)
			(end -0.67945 -0.3048)
			(stroke
				(width 0.1)
				(type default)
			)
			(layer "B.Fab")
		)
		(fp_line
			(start 0.12065 -0.305054)
			(end 0.12065 -0.2794)
			(stroke
				(width 0.1)
				(type default)
			)
			(layer "B.Fab")
		)
		(fp_line
			(start 0.67945 -0.305054)
			(end 0.12065 -0.305054)
			(stroke
				(width 0.1)
				(type default)
			)
			(layer "B.Fab")
		)
		(pad "1" smd circle
			(at 0.40005 0 90)
			(size 0 0)
			(layers "B.Cu" "B.Mask" "B.Paste")
			(net "PVDDCR_CPU1_P0_VOS1")
		)
		(pad "2" smd circle
			(at -0.40005 0 90)
			(size 0 0)
			(layers "B.Cu" "B.Mask" "B.Paste")
			(net "PVDDCR_CPU1_P0")
		)
	)
	(footprint ""
		(layer "B.Cu")
		(at 115.277138 -261.748016 90)
		(property "Reference" "C2497"
			(at 0 0 90)
			(layer "B.SilkS")
			(hide yes)
			(effects
				(font
					(size 1.27 1.27)
				)
				(justify mirror)
			)
		)
		(property "Value" ""
			(at 0 0 90)
			(layer "B.Fab")
			(effects
				(font
					(size 1.27 1.27)
				)
				(justify mirror)
			)
		)
		(duplicate_pad_numbers_are_jumpers no)
		(fp_line
			(start 0.7874 -0.4064)
			(end -0.7874 -0.4064)
			(stroke
				(width 0.1524)
				(type default)
			)
			(layer "B.SilkS")
		)
		(fp_line
			(start -0.7874 -0.4064)
			(end -0.7874 0.4064)
			(stroke
				(width 0.1524)
				(type default)
			)
			(layer "B.SilkS")
		)
		(fp_line
			(start 0.7874 0.4064)
			(end 0.7874 -0.4064)
			(stroke
				(width 0.1524)
				(type default)
			)
			(layer "B.SilkS")
		)
		(fp_line
			(start -0.7874 0.4064)
			(end 0.7874 0.4064)
			(stroke
				(width 0.1524)
				(type default)
			)
			(layer "B.SilkS")
		)
		(fp_line
			(start 0.67945 -0.305054)
			(end 0.12065 -0.305054)
			(stroke
				(width 0.1)
				(type default)
			)
			(layer "B.Fab")
		)
		(fp_line
			(start 0.12065 -0.305054)
			(end 0.12065 -0.2794)
			(stroke
				(width 0.1)
				(type default)
			)
			(layer "B.Fab")
		)
		(fp_line
			(start -0.12065 -0.3048)
			(end -0.67945 -0.3048)
			(stroke
				(width 0.1)
				(type default)
			)
			(layer "B.Fab")
		)
		(fp_line
			(start -0.67945 -0.3048)
			(end -0.67945 0.3048)
			(stroke
				(width 0.1)
				(type default)
			)
			(layer "B.Fab")
		)
		(fp_line
			(start 0.12065 -0.2794)
			(end -0.12065 -0.2794)
			(stroke
				(width 0.1)
				(type default)
			)
			(layer "B.Fab")
		)
		(fp_line
			(start -0.12065 -0.2794)
			(end -0.12065 -0.3048)
			(stroke
				(width 0.1)
				(type default)
			)
			(layer "B.Fab")
		)
		(fp_line
			(start 0.12065 0.2794)
			(end 0.12065 0.3048)
			(stroke
				(width 0.1)
				(type default)
			)
			(layer "B.Fab")
		)
		(fp_line
			(start -0.120396 0.2794)
			(end 0.12065 0.2794)
			(stroke
				(width 0.1)
				(type default)
			)
			(layer "B.Fab")
		)
		(fp_line
			(start 0.67945 0.3048)
			(end 0.67945 -0.305054)
			(stroke
				(width 0.1)
				(type default)
			)
			(layer "B.Fab")
		)
		(fp_line
			(start 0.12065 0.3048)
			(end 0.67945 0.3048)
			(stroke
				(width 0.1)
				(type default)
			)
			(layer "B.Fab")
		)
		(fp_line
			(start -0.120396 0.3048)
			(end -0.120396 0.2794)
			(stroke
				(width 0.1)
				(type default)
			)
			(layer "B.Fab")
		)
		(fp_line
			(start -0.67945 0.3048)
			(end -0.120396 0.3048)
			(stroke
				(width 0.1)
				(type default)
			)
			(layer "B.Fab")
		)
		(pad "1" smd circle
			(at 0.40005 0 270)
			(size 0 0)
			(layers "B.Cu" "B.Mask" "B.Paste")
			(net "PVDD11_S3_P1")
		)
		(pad "2" smd circle
			(at -0.40005 0 270)
			(size 0 0)
			(layers "B.Cu" "B.Mask" "B.Paste")
			(net "GND")
		)
	)
)
